# T6G (Grand Teton) — schematic netlist excerpt (pin names and nets, part order shuffled) for the footprints in the layout excerpt that follows; sources: Cadence DE-HDL packaged netlist, KiCad conversion of 04192023_DAF0TMB3IC0_F0TG_MB_C_brd_V02_OCP.brd

R212  Q_RES  33 5% CHIP  pkg 0402LF  page 28 : A = SMB_CPU_5_R_SCL ; B = SMB_CPU_5_SCL
C6003  Q_CAP  0.1UF 25V 10% X7R  pkg 0402  page 180 : A = USB3_CPU0_BMC_TX_DP ; B = USB3_CPU0_BMC_TX_C1_DP
H43  HOLE  EMPTY  pkg TH  page 230 : \1\ = GND

(kicad_pcb
	(version 20260206)
	(generator "pcbnew")
	(generator_version "10.0")
	(general
		(thickness 1.6)
		(legacy_teardrops no)
	)
	(paper "A4")
	(title_block
		(title "04192023_DAF0TMB3IC0_F0TG_MB_C_brd_V02_OCP.brd")
		(comment 1 "Grand Teton / footprints 785-787 of 8354")
	)
	(layers
		(0 "F.Cu" signal "TOP")
		(4 "In1.Cu" signal "GND")
		(6 "In2.Cu" signal "IN1")
		(8 "In3.Cu" signal "GND1")
		(10 "In4.Cu" signal "IN2")
		(12 "In5.Cu" signal "GND2")
		(14 "In6.Cu" signal "IN3")
		(16 "In7.Cu" signal "GND3")
		(18 "In8.Cu" signal "VCC")
		(20 "In9.Cu" signal "VCC1")
		(22 "In10.Cu" signal "GND4")
		(24 "In11.Cu" signal "IN4")
		(26 "In12.Cu" signal "GND5")
		(28 "In13.Cu" signal "IN5")
		(30 "In14.Cu" signal "GND6")
		(32 "In15.Cu" signal "IN6")
		(34 "In16.Cu" signal "GND7")
		(2 "B.Cu" signal "BOTTOM")
		(9 "F.Adhes" user "F.Adhesive")
		(11 "B.Adhes" user "B.Adhesive")
		(13 "F.Paste" user "Package Geometry/Pastemask Top")
		(15 "B.Paste" user "Package Geometry/Pastemask Bottom")
		(5 "F.SilkS" user "Ref Des/Silkscreen Top")
		(7 "B.SilkS" user "Ref Des/Silkscreen Bottom")
		(1 "F.Mask" user "Board Geometry/Soldermask Top")
		(3 "B.Mask" user "Board Geometry/Soldermask Bottom")
		(17 "Dwgs.User" user "User.Drawings")
		(19 "Cmts.User" user "User.Comments")
		(21 "Eco1.User" user "User.Eco1")
		(23 "Eco2.User" user "User.Eco2")
		(25 "Edge.Cuts" user "Board Geometry/Outline")
		(27 "Margin" user)
		(31 "F.CrtYd" user "Package Geometry/Place Bound Top")
		(29 "B.CrtYd" user "Package Geometry/Place Bound Bottom")
		(35 "F.Fab" user "Ref Des/Assembly Top")
		(33 "B.Fab" user "Ref Des/Assembly Bottom")
	)
	(footprint ""
		(layer "F.Cu")
		(at 393.363958 -326.691752)
		(property "Reference" "R212"
			(at 0 0 0)
			(layer "F.SilkS")
			(hide yes)
			(effects
				(font
					(size 1.27 1.27)
				)
			)
		)
		(property "Value" ""
			(at 0 0 0)
			(layer "F.Fab")
			(effects
				(font
					(size 1.27 1.27)
				)
			)
		)
		(duplicate_pad_numbers_are_jumpers no)
		(fp_line
			(start -0.7874 -0.4064)
			(end 0.7874 -0.4064)
			(stroke
				(width 0.1524)
				(type default)
			)
			(layer "F.SilkS")
		)
		(fp_line
			(start -0.7874 0.4064)
			(end -0.7874 -0.4064)
			(stroke
				(width 0.1524)
				(type default)
			)
			(layer "F.SilkS")
		)
		(fp_line
			(start 0.7874 -0.4064)
			(end 0.7874 0.4064)
			(stroke
				(width 0.1524)
				(type default)
			)
			(layer "F.SilkS")
		)
		(fp_line
			(start 0.7874 0.4064)
			(end -0.7874 0.4064)
			(stroke
				(width 0.1524)
				(type default)
			)
			(layer "F.SilkS")
		)
		(fp_line
			(start -0.67945 -0.305054)
			(end -0.12065 -0.305054)
			(stroke
				(width 0.1)
				(type default)
			)
			(layer "F.Fab")
		)
		(fp_line
			(start -0.67945 0.3048)
			(end -0.67945 -0.305054)
			(stroke
				(width 0.1)
				(type default)
			)
			(layer "F.Fab")
		)
		(fp_line
			(start -0.12065 -0.305054)
			(end -0.12065 -0.2794)
			(stroke
				(width 0.1)
				(type default)
			)
			(layer "F.Fab")
		)
		(fp_line
			(start -0.12065 -0.2794)
			(end 0.12065 -0.2794)
			(stroke
				(width 0.1)
				(type default)
			)
			(layer "F.Fab")
		)
		(fp_line
			(start -0.12065 0.2794)
			(end -0.12065 0.3048)
			(stroke
				(width 0.1)
				(type default)
			)
			(layer "F.Fab")
		)
		(fp_line
			(start -0.12065 0.3048)
			(end -0.67945 0.3048)
			(stroke
				(width 0.1)
				(type default)
			)
			(layer "F.Fab")
		)
		(fp_line
			(start 0.120396 0.2794)
			(end -0.12065 0.2794)
			(stroke
				(width 0.1)
				(type default)
			)
			(layer "F.Fab")
		)
		(fp_line
			(start 0.120396 0.3048)
			(end 0.120396 0.2794)
			(stroke
				(width 0.1)
				(type default)
			)
			(layer "F.Fab")
		)
		(fp_line
			(start 0.12065 -0.3048)
			(end 0.67945 -0.3048)
			(stroke
				(width 0.1)
				(type default)
			)
			(layer "F.Fab")
		)
		(fp_line
			(start 0.12065 -0.2794)
			(end 0.12065 -0.3048)
			(stroke
				(width 0.1)
				(type default)
			)
			(layer "F.Fab")
		)
		(fp_line
			(start 0.67945 -0.3048)
			(end 0.67945 0.3048)
			(stroke
				(width 0.1)
				(type default)
			)
			(layer "F.Fab")
		)
		(fp_line
			(start 0.67945 0.3048)
			(end 0.120396 0.3048)
			(stroke
				(width 0.1)
				(type default)
			)
			(layer "F.Fab")
		)
		(pad "1" smd circle
			(at -0.40005 0)
			(size 0 0)
			(layers "F.Cu" "F.Mask" "F.Paste")
			(net "SMB_CPU_5_R_SCL")
		)
		(pad "2" smd circle
			(at 0.40005 0)
			(size 0 0)
			(layers "F.Cu" "F.Mask" "F.Paste")
			(net "SMB_CPU_5_SCL")
		)
	)
	(footprint ""
		(layer "F.Cu")
		(at 106.71175 -166.626032)
		(property "Reference" "H43"
			(at -5.286502 -3.414776 0)
			(unlocked yes)
			(layer "F.SilkS")
			(effects
				(font
					(size 0.7874 0.5842)
					(thickness 0.1524)
				)
				(justify left)
			)
		)
		(property "Value" ""
			(at 0 0 0)
			(layer "F.Fab")
			(effects
				(font
					(size 1.27 1.27)
				)
			)
		)
		(duplicate_pad_numbers_are_jumpers no)
		(pad "1" thru_hole circle
			(at 0 0)
			(size 6.1976 6.1976)
			(drill 3.7338)
			(layers "*.Cu" "*.Mask")
			(remove_unused_layers no)
			(net "GND")
			(clearance -0.9779)
			(padstack
				(mode front_inner_back)
				(layer "Inner"
					(shape circle)
					(size 5.5372 5.5372)
					(clearance -0.6477)
				)
				(layer "B.Cu"
					(shape circle)
					(size 6.1976 6.1976)
					(clearance -0.9779)
				)
			)
		)
	)
	(footprint ""
		(layer "F.Cu")
		(at 145.63344 -31.58744 90)
		(property "Reference" "C6003"
			(at 0 0 90)
			(layer "F.SilkS")
			(hide yes)
			(effects
				(font
					(size 1.27 1.27)
				)
			)
		)
		(property "Value" ""
			(at 0 0 90)
			(layer "F.Fab")
			(effects
				(font
					(size 1.27 1.27)
				)
			)
		)
		(duplicate_pad_numbers_are_jumpers no)
		(fp_line
			(start 0.7874 -0.4064)
			(end 0.7874 0.4064)
			(stroke
				(width 0.1524)
				(type default)
			)
			(layer "F.SilkS")
		)
		(fp_line
			(start -0.7874 -0.4064)
			(end 0.7874 -0.4064)
			(stroke
				(width 0.1524)
				(type default)
			)
			(layer "F.SilkS")
		)
		(fp_line
			(start 0.7874 0.4064)
			(end -0.7874 0.4064)
			(stroke
				(width 0.1524)
				(type default)
			)
			(layer "F.SilkS")
		)
		(fp_line
			(start -0.7874 0.4064)
			(end -0.7874 -0.4064)
			(stroke
				(width 0.1524)
				(type default)
			)
			(layer "F.SilkS")
		)
		(fp_line
			(start 0.6858 -0.3048)
			(end 0.6858 0.3048)
			(stroke
				(width 0.1)
				(type default)
			)
			(layer "F.Fab")
		)
		(fp_line
			(start 0.1016 -0.3048)
			(end 0.6858 -0.3048)
			(stroke
				(width 0.1)
				(type default)
			)
			(layer "F.Fab")
		)
		(fp_line
			(start -0.1016 -0.3048)
			(end -0.1016 -0.2794)
			(stroke
				(width 0.1)
				(type default)
			)
			(layer "F.Fab")
		)
		(fp_line
			(start -0.6858 -0.3048)
			(end -0.1016 -0.3048)
			(stroke
				(width 0.1)
				(type default)
			)
			(layer "F.Fab")
		)
		(fp_line
			(start 0.1016 -0.2794)
			(end 0.1016 -0.3048)
			(stroke
				(width 0.1)
				(type default)
			)
			(layer "F.Fab")
		)
		(fp_line
			(start -0.1016 -0.2794)
			(end 0.1016 -0.2794)
			(stroke
				(width 0.1)
				(type default)
			)
			(layer "F.Fab")
		)
		(fp_line
			(start 0.1016 0.2794)
			(end -0.1016 0.2794)
			(stroke
				(width 0.1)
				(type default)
			)
			(layer "F.Fab")
		)
		(fp_line
			(start -0.1016 0.2794)
			(end -0.1016 0.3048)
			(stroke
				(width 0.1)
				(type default)
			)
			(layer "F.Fab")
		)
		(fp_line
			(start 0.6858 0.3048)
			(end 0.1016 0.3048)
			(stroke
				(width 0.1)
				(type default)
			)
			(layer "F.Fab")
		)
		(fp_line
			(start 0.1016 0.3048)
			(end 0.1016 0.2794)
			(stroke
				(width 0.1)
				(type default)
			)
			(layer "F.Fab")
		)
		(fp_line
			(start -0.1016 0.3048)
			(end -0.6858 0.3048)
			(stroke
				(width 0.1)
				(type default)
			)
			(layer "F.Fab")
		)
		(fp_line
			(start -0.6858 0.3048)
			(end -0.6858 -0.3048)
			(stroke
				(width 0.1)
				(type default)
			)
			(layer "F.Fab")
		)
		(pad "1" smd rect
			(at -0.40005 0 270)
			(size 0.4572 0.508)
			(layers "F.Cu" "F.Mask" "F.Paste")
			(net "USB3_CPU0_BMC_TX_DP")
		)
		(pad "2" smd rect
			(at 0.40005 0 270)
			(size 0.4572 0.508)
			(layers "F.Cu" "F.Mask" "F.Paste")
			(net "USB3_CPU0_BMC_TX_C1_DP")
		)
	)
)
